(kicad_pcb
	(version 20241229)
	(generator "pcbnew")
	(generator_version "9.0")
	(general
		(thickness 1.711)
		(legacy_teardrops no)
	)
	(paper "A4")
	(title_block
		(title "Antmicro Baseboard for Jetson AGX Thor")
		(date "2026-02-18")
		(rev "1.1.0")
		(company "Antmicro Ltd")
		(comment 1 "www.antmicro.com")
		(comment 9 "footprints 142-144 of 1170")
	)
	(layers
		(0 "F.Cu" signal)
		(4 "In1.Cu" signal)
		(6 "In2.Cu" signal)
		(8 "In3.Cu" signal)
		(10 "In4.Cu" jumper)
		(12 "In5.Cu" signal)
		(14 "In6.Cu" signal)
		(16 "In7.Cu" signal)
		(18 "In8.Cu" signal)
		(2 "B.Cu" signal)
		(9 "F.Adhes" user "F.Adhesive")
		(11 "B.Adhes" user "B.Adhesive")
		(13 "F.Paste" user)
		(15 "B.Paste" user)
		(5 "F.SilkS" user "F.Silkscreen")
		(7 "B.SilkS" user "B.Silkscreen")
		(1 "F.Mask" user)
		(3 "B.Mask" user)
		(17 "Dwgs.User" user "User.Drawings")
		(19 "Cmts.User" user "User.Comments")
		(21 "Eco1.User" user "User.Eco1")
		(23 "Eco2.User" user "User.Eco2")
		(25 "Edge.Cuts" user)
		(27 "Margin" user)
		(31 "F.CrtYd" user "F.Courtyard")
		(29 "B.CrtYd" user "B.Courtyard")
		(35 "F.Fab" user)
		(33 "B.Fab" user)
	)
	(footprint "antmicro-footprints:TP_SMD_0.75mm"
		(layer "F.Cu")
		(at 69.279 63.231 90)
		(property "Reference" "TP21"
			(at 0.39 3.17 0)
			(layer "F.SilkS")
			(effects
				(font
					(size 0.7 0.7)
					(thickness 0.15)
				)
				(justify right top)
			)
		)
		(property "Value" "TP_0.75mm_SMD"
			(at 0 1.2 90)
			(layer "F.Fab")
			(effects
				(font
					(size 0.7 0.7)
					(thickness 0.15)
				)
				(justify left bottom)
			)
		)
		(property "Description" "SMT test point"
			(at 0 0 90)
			(layer "F.Fab")
			(hide yes)
			(effects
				(font
					(size 1.27 1.27)
					(thickness 0.15)
				)
			)
		)
		(property "MPN" ""
			(at 0 0 90)
			(unlocked yes)
			(layer "F.Fab")
			(hide yes)
			(effects
				(font
					(size 1 1)
					(thickness 0.15)
				)
			)
		)
		(property "Manufacturer" ""
			(at 0 0 90)
			(unlocked yes)
			(layer "F.Fab")
			(hide yes)
			(effects
				(font
					(size 1 1)
					(thickness 0.15)
				)
			)
		)
		(property "Author" "Antmicro"
			(at 0 0 90)
			(unlocked yes)
			(layer "F.Fab")
			(hide yes)
			(effects
				(font
					(size 1 1)
					(thickness 0.15)
				)
			)
		)
		(property "License" "Apache-2.0"
			(at 0 0 90)
			(unlocked yes)
			(layer "F.Fab")
			(hide yes)
			(effects
				(font
					(size 1 1)
					(thickness 0.15)
				)
			)
		)
		(sheetname "/CSI/")
		(sheetfile "csi.kicad_sch")
		(attr exclude_from_pos_files exclude_from_bom)
		(fp_circle
			(center 0 0)
			(end 0.475 0)
			(stroke
				(width 0.05)
				(type default)
			)
			(fill no)
			(layer "F.CrtYd")
		)
		(fp_text user "Author: Antmicro"
			(at -0.4 3.901 90)
			(layer "F.Fab")
			(effects
				(font
					(size 0.7 0.7)
					(thickness 0.15)
				)
				(justify left bottom)
			)
		)
		(fp_text user "${REFERENCE}"
			(at -0.4 2.7 90)
			(layer "F.Fab")
			(effects
				(font
					(size 0.7 0.7)
					(thickness 0.15)
				)
				(justify left bottom)
			)
		)
		(fp_text user "License: Apache-2.0"
			(at -0.4 5.101 90)
			(layer "F.Fab")
			(effects
				(font
					(size 0.7 0.7)
					(thickness 0.15)
				)
				(justify left bottom)
			)
		)
		(pad "1" smd circle
			(at 0 0 90)
			(size 0.75 0.75)
			(layers "F.Cu" "F.Mask")
			(net 1045 "/CSI/MUX_I2C_4_SDA")
			(pinfunction "1")
			(pintype "passive")
		)
	)
	(footprint "antmicro-footprints:C_0402_1005Metric"
		(layer "F.Cu")
		(at 91.1 101.2)
		(descr "Capacitor SMD 0402")
		(tags "capacitor SMD 0402")
		(property "Reference" "C348"
			(at 1.1 0.5 0)
			(layer "F.SilkS")
			(effects
				(font
					(size 0.7 0.7)
					(thickness 0.15)
				)
				(justify left bottom)
			)
		)
		(property "Value" "C_100n_0402"
			(at -1.022927 2.155213 0)
			(layer "F.Fab")
			(effects
				(font
					(size 0.7 0.7)
					(thickness 0.15)
				)
				(justify left bottom)
			)
		)
		(property "Datasheet" "https://www.murata.com/products/productdetail?partno=GRM155R61H104KE14%23"
			(at 0 0 0)
			(layer "F.Fab")
			(hide yes)
			(effects
				(font
					(size 1.27 1.27)
					(thickness 0.15)
				)
			)
		)
		(property "Description" "SMD Multilayer Ceramic Capacitor, 0.1 µF, 50 V, 0402 [1005 Metric], ± 10%, X5R, GRM Series"
			(at 0 0 0)
			(layer "F.Fab")
			(hide yes)
			(effects
				(font
					(size 1.27 1.27)
					(thickness 0.15)
				)
			)
		)
		(property "Manufacturer" "Murata"
			(at 0 0 0)
			(unlocked yes)
			(layer "F.Fab")
			(hide yes)
			(effects
				(font
					(size 1 1)
					(thickness 0.15)
				)
			)
		)
		(property "MPN" "GRM155R61H104KE14D"
			(at 0 0 0)
			(unlocked yes)
			(layer "F.Fab")
			(hide yes)
			(effects
				(font
					(size 1 1)
					(thickness 0.15)
				)
			)
		)
		(property "Val" "100n"
			(at 0 0 0)
			(unlocked yes)
			(layer "F.Fab")
			(hide yes)
			(effects
				(font
					(size 1 1)
					(thickness 0.15)
				)
			)
		)
		(property "License" "Apache-2.0"
			(at 0 0 0)
			(unlocked yes)
			(layer "F.Fab")
			(hide yes)
			(effects
				(font
					(size 1 1)
					(thickness 0.15)
				)
			)
		)
		(property "Author" "Antmicro"
			(at 0 0 0)
			(unlocked yes)
			(layer "F.Fab")
			(hide yes)
			(effects
				(font
					(size 1 1)
					(thickness 0.15)
				)
			)
		)
		(property "Voltage" "50V"
			(at 0 0 0)
			(unlocked yes)
			(layer "F.Fab")
			(hide yes)
			(effects
				(font
					(size 1 1)
					(thickness 0.15)
				)
			)
		)
		(property "Dielectric" "X5R"
			(at 0 0 0)
			(unlocked yes)
			(layer "F.Fab")
			(hide yes)
			(effects
				(font
					(size 1 1)
					(thickness 0.15)
				)
			)
		)
		(sheetname "/SoM_IO2/")
		(sheetfile "som_io2.kicad_sch")
		(attr smd)
		(fp_poly
			(pts
				(xy -0.925 -0.47) (xy 0.925 -0.47) (xy 0.925 0.47) (xy -0.925 0.47)
			)
			(stroke
				(width 0.05)
				(type default)
			)
			(fill no)
			(layer "F.CrtYd")
		)
		(fp_line
			(start -0.494 -0.25)
			(end 0.504 -0.25)
			(stroke
				(width 0.15)
				(type solid)
			)
			(layer "F.Fab")
		)
		(fp_line
			(start -0.494 0.248)
			(end -0.494 -0.25)
			(stroke
				(width 0.15)
				(type solid)
			)
			(layer "F.Fab")
		)
		(fp_line
			(start 0.504 -0.25)
			(end 0.504 0.248)
			(stroke
				(width 0.15)
				(type solid)
			)
			(layer "F.Fab")
		)
		(fp_line
			(start 0.504 0.248)
			(end -0.494 0.248)
			(stroke
				(width 0.15)
				(type solid)
			)
			(layer "F.Fab")
		)
		(fp_text user "Author: Antmicro"
			(at -0.939 3.399 0)
			(layer "F.Fab")
			(effects
				(font
					(size 0.7 0.7)
					(thickness 0.15)
				)
				(justify left bottom)
			)
		)
		(fp_text user "License: Apache-2.0"
			(at -0.939 5.799 0)
			(layer "F.Fab")
			(effects
				(font
					(size 0.7 0.7)
					(thickness 0.15)
				)
				(justify left bottom)
			)
		)
		(fp_text user "${REFERENCE}"
			(at -0.939 4.599 0)
			(layer "F.Fab")
			(effects
				(font
					(size 0.7 0.7)
					(thickness 0.15)
				)
				(justify left bottom)
			)
		)
		(pad "1" smd roundrect
			(at -0.48 0)
			(size 0.59 0.64)
			(layers "F.Cu" "F.Mask" "F.Paste")
			(roundrect_rratio 0.25)
			(net 665 "/Expansion connector/DP3.TX0-")
			(pintype "passive")
		)
		(pad "2" smd roundrect
			(at 0.48 0)
			(size 0.59 0.64)
			(layers "F.Cu" "F.Mask" "F.Paste")
			(roundrect_rratio 0.25)
			(net 1268 "/SoM_IO2/DP3.TX0_C-")
			(pintype "passive")
		)
	)
	(footprint "antmicro-footprints:R_0402_1005Metric"
		(layer "F.Cu")
		(at 219.77 73.599951 180)
		(descr "Resistor SMD 0402")
		(tags "resistor SMD 0402")
		(property "Reference" "R119"
			(at 1.37 -2.550049 180)
			(layer "F.SilkS")
			(effects
				(font
					(size 0.7 0.7)
					(thickness 0.15)
				)
				(justify left bottom)
			)
		)
		(property "Value" "R_200R_0402"
			(at -1.011843 1.772047 180)
			(layer "F.Fab")
			(effects
				(font
					(size 0.7 0.7)
					(thickness 0.15)
				)
				(justify left bottom)
			)
		)
		(property "Datasheet" "https://www.bourns.com/docs/product-datasheets/cr.pdf"
			(at 0 0 180)
			(layer "F.Fab")
			(hide yes)
			(effects
				(font
					(size 1.27 1.27)
					(thickness 0.15)
				)
			)
		)
		(property "Description" "SMD Chip Resistor, 200 ohm, ± 1%, 62.5 mW, 0402 [1005 Metric], Thick Film, General Purpose"
			(at 0 0 180)
			(layer "F.Fab")
			(hide yes)
			(effects
				(font
					(size 1.27 1.27)
					(thickness 0.15)
				)
			)
		)
		(property "Manufacturer" "Bourns"
			(at 0 0 180)
			(unlocked yes)
			(layer "F.Fab")
			(hide yes)
			(effects
				(font
					(size 1 1)
					(thickness 0.15)
				)
			)
		)
		(property "MPN" "CR0402-FX-2000GLF"
			(at 0 0 180)
			(unlocked yes)
			(layer "F.Fab")
			(hide yes)
			(effects
				(font
					(size 1 1)
					(thickness 0.15)
				)
			)
		)
		(property "Val" "200R"
			(at 0 0 180)
			(unlocked yes)
			(layer "F.Fab")
			(hide yes)
			(effects
				(font
					(size 1 1)
					(thickness 0.15)
				)
			)
		)
		(property "License" "Apache-2.0"
			(at 0 0 180)
			(unlocked yes)
			(layer "F.Fab")
			(hide yes)
			(effects
				(font
					(size 1 1)
					(thickness 0.15)
				)
			)
		)
		(property "Author" "Antmicro"
			(at 0 0 180)
			(unlocked yes)
			(layer "F.Fab")
			(hide yes)
			(effects
				(font
					(size 1 1)
					(thickness 0.15)
				)
			)
		)
		(property "Tolerance" "1%"
			(at 0 0 180)
			(unlocked yes)
			(layer "F.Fab")
			(hide yes)
			(effects
				(font
					(size 1 1)
					(thickness 0.15)
				)
			)
		)
		(sheetname "/USB Debug, PD/")
		(sheetfile "usb_debug_pd.kicad_sch")
		(attr smd)
		(fp_rect
			(start -0.925 -0.47)
			(end 0.925 0.47)
			(stroke
				(width 0.05)
				(type default)
			)
			(fill no)
			(layer "F.CrtYd")
		)
		(fp_rect
			(start -0.5 -0.25)
			(end 0.5 0.25)
			(stroke
				(width 0.15)
				(type solid)
			)
			(fill no)
			(layer "F.Fab")
		)
		(fp_text user "Author: Antmicro"
			(at -0.95 4.169 180)
			(layer "F.Fab")
			(effects
				(font
					(size 0.7 0.7)
					(thickness 0.15)
				)
				(justify left bottom)
			)
		)
		(fp_text user "License: Apache-2.0"
			(at -0.95 5.169 180)
			(layer "F.Fab")
			(effects
				(font
					(size 0.7 0.7)
					(thickness 0.15)
				)
				(justify left bottom)
			)
		)
		(fp_text user "${REFERENCE}"
			(at -0.95 3.168 180)
			(layer "F.Fab")
			(effects
				(font
					(size 0.7 0.7)
					(thickness 0.15)
				)
				(justify left bottom)
			)
		)
		(pad "1" smd roundrect
			(at -0.48 0 180)
			(size 0.59 0.64)
			(layers "F.Cu" "F.Mask" "F.Paste")
			(roundrect_rratio 0.25)
			(net 535 "Net-(D20-A)")
			(pintype "passive")
		)
		(pad "2" smd roundrect
			(at 0.48 0 180)
			(size 0.59 0.64)
			(layers "F.Cu" "F.Mask" "F.Paste")
			(roundrect_rratio 0.25)
			(net 334 "/USB Debug, PD/FTDI_3V3")
			(pintype "passive")
		)
	)
)
